(kicad_pcb
	(version 20260206)
	(generator "pcbnew")
	(generator_version "10.0")
	(general
		(thickness 1.6)
		(legacy_teardrops no)
	)
	(paper "A4")
	(title_block
		(title "12092022_DA0F0TFB6D0_F0T_FAN_BOARD_MP5048_D_brd_v02_OCP.brd")
		(comment 1 "Grand Teton / footprints 274-279 of 924")
	)
	(layers
		(0 "F.Cu" signal "TOP")
		(4 "In1.Cu" signal "GND")
		(6 "In2.Cu" signal "IN1")
		(8 "In3.Cu" signal "IN2")
		(10 "In4.Cu" signal "GND1")
		(2 "B.Cu" signal "BOTTOM")
		(9 "F.Adhes" user "F.Adhesive")
		(11 "B.Adhes" user "B.Adhesive")
		(13 "F.Paste" user "Package Geometry/Pastemask Top")
		(15 "B.Paste" user "Package Geometry/Pastemask Bottom")
		(5 "F.SilkS" user "Ref Des/Silkscreen Top")
		(7 "B.SilkS" user "Ref Des/Silkscreen Bottom")
		(1 "F.Mask" user "Board Geometry/Soldermask Top")
		(3 "B.Mask" user "Board Geometry/Soldermask Bottom")
		(17 "Dwgs.User" user "User.Drawings")
		(19 "Cmts.User" user "User.Comments")
		(21 "Eco1.User" user "User.Eco1")
		(23 "Eco2.User" user "User.Eco2")
		(25 "Edge.Cuts" user "Board Geometry/Outline")
		(27 "Margin" user)
		(31 "F.CrtYd" user "Package Geometry/Place Bound Top")
		(29 "B.CrtYd" user "Package Geometry/Place Bound Bottom")
		(35 "F.Fab" user "Ref Des/Assembly Top")
		(33 "B.Fab" user "Ref Des/Assembly Bottom")
	)
	(footprint ""
		(layer "F.Cu")
		(at 20.955 -218.059)
		(property "Reference" "C2126"
			(at 0 0 0)
			(layer "F.SilkS")
			(hide yes)
			(effects
				(font
					(size 1.27 1.27)
				)
			)
		)
		(property "Value" ""
			(at 0 0 0)
			(layer "F.Fab")
			(effects
				(font
					(size 1.27 1.27)
				)
			)
		)
		(duplicate_pad_numbers_are_jumpers no)
		(fp_line
			(start -1.2954 -0.5842)
			(end 1.2954 -0.5842)
			(stroke
				(width 0.1524)
				(type default)
			)
			(layer "F.SilkS")
		)
		(fp_line
			(start -1.2954 0.5842)
			(end -1.2954 -0.5842)
			(stroke
				(width 0.1524)
				(type default)
			)
			(layer "F.SilkS")
		)
		(fp_line
			(start 1.2954 -0.5842)
			(end 1.2954 0.5842)
			(stroke
				(width 0.1524)
				(type default)
			)
			(layer "F.SilkS")
		)
		(fp_line
			(start 1.2954 0.5842)
			(end -1.2954 0.5842)
			(stroke
				(width 0.1524)
				(type default)
			)
			(layer "F.SilkS")
		)
		(fp_line
			(start -1.1938 -0.4064)
			(end -0.8636 -0.4064)
			(stroke
				(width 0.1)
				(type default)
			)
			(layer "F.Fab")
		)
		(fp_line
			(start -1.1938 0.4064)
			(end -1.1938 -0.4064)
			(stroke
				(width 0.1)
				(type default)
			)
			(layer "F.Fab")
		)
		(fp_line
			(start -0.8636 -0.4572)
			(end 0.8636 -0.4572)
			(stroke
				(width 0.1)
				(type default)
			)
			(layer "F.Fab")
		)
		(fp_line
			(start -0.8636 -0.4064)
			(end -0.8636 -0.4572)
			(stroke
				(width 0.1)
				(type default)
			)
			(layer "F.Fab")
		)
		(fp_line
			(start -0.8636 0.4064)
			(end -1.1938 0.4064)
			(stroke
				(width 0.1)
				(type default)
			)
			(layer "F.Fab")
		)
		(fp_line
			(start -0.8636 0.4572)
			(end -0.8636 0.4064)
			(stroke
				(width 0.1)
				(type default)
			)
			(layer "F.Fab")
		)
		(fp_line
			(start 0.8636 -0.4572)
			(end 0.8636 -0.4064)
			(stroke
				(width 0.1)
				(type default)
			)
			(layer "F.Fab")
		)
		(fp_line
			(start 0.8636 -0.4064)
			(end 1.1938 -0.4064)
			(stroke
				(width 0.1)
				(type default)
			)
			(layer "F.Fab")
		)
		(fp_line
			(start 0.8636 0.4064)
			(end 0.8636 0.4572)
			(stroke
				(width 0.1)
				(type default)
			)
			(layer "F.Fab")
		)
		(fp_line
			(start 0.8636 0.4572)
			(end -0.8636 0.4572)
			(stroke
				(width 0.1)
				(type default)
			)
			(layer "F.Fab")
		)
		(fp_line
			(start 1.1938 -0.4064)
			(end 1.1938 0.4064)
			(stroke
				(width 0.1)
				(type default)
			)
			(layer "F.Fab")
		)
		(fp_line
			(start 1.1938 0.4064)
			(end 0.8636 0.4064)
			(stroke
				(width 0.1)
				(type default)
			)
			(layer "F.Fab")
		)
		(pad "1" smd rect
			(at -0.7366 0 270)
			(size 0.7112 0.8128)
			(layers "F.Cu" "F.Mask" "F.Paste")
			(net "U411_D1")
		)
		(pad "2" smd rect
			(at 0.7366 0 270)
			(size 0.7112 0.8128)
			(layers "F.Cu" "F.Mask" "F.Paste")
			(net "GND")
		)
	)
	(footprint ""
		(layer "F.Cu")
		(at 35.179 -207.038956 180)
		(property "Reference" "C2029"
			(at 0 0 180)
			(layer "F.SilkS")
			(hide yes)
			(effects
				(font
					(size 1.27 1.27)
				)
			)
		)
		(property "Value" ""
			(at 0 0 180)
			(layer "F.Fab")
			(effects
				(font
					(size 1.27 1.27)
				)
			)
		)
		(duplicate_pad_numbers_are_jumpers no)
		(fp_line
			(start 0.7874 0.4064)
			(end -0.7874 0.4064)
			(stroke
				(width 0.1524)
				(type default)
			)
			(layer "F.SilkS")
		)
		(fp_line
			(start 0.7874 -0.4064)
			(end 0.7874 0.4064)
			(stroke
				(width 0.1524)
				(type default)
			)
			(layer "F.SilkS")
		)
		(fp_line
			(start -0.7874 0.4064)
			(end -0.7874 -0.4064)
			(stroke
				(width 0.1524)
				(type default)
			)
			(layer "F.SilkS")
		)
		(fp_line
			(start -0.7874 -0.4064)
			(end 0.7874 -0.4064)
			(stroke
				(width 0.1524)
				(type default)
			)
			(layer "F.SilkS")
		)
		(fp_line
			(start 0.67945 0.3048)
			(end 0.120396 0.3048)
			(stroke
				(width 0.1)
				(type default)
			)
			(layer "F.Fab")
		)
		(fp_line
			(start 0.67945 -0.3048)
			(end 0.67945 0.3048)
			(stroke
				(width 0.1)
				(type default)
			)
			(layer "F.Fab")
		)
		(fp_line
			(start 0.12065 -0.2794)
			(end 0.12065 -0.3048)
			(stroke
				(width 0.1)
				(type default)
			)
			(layer "F.Fab")
		)
		(fp_line
			(start 0.12065 -0.3048)
			(end 0.67945 -0.3048)
			(stroke
				(width 0.1)
				(type default)
			)
			(layer "F.Fab")
		)
		(fp_line
			(start 0.120396 0.3048)
			(end 0.120396 0.2794)
			(stroke
				(width 0.1)
				(type default)
			)
			(layer "F.Fab")
		)
		(fp_line
			(start 0.120396 0.2794)
			(end -0.12065 0.2794)
			(stroke
				(width 0.1)
				(type default)
			)
			(layer "F.Fab")
		)
		(fp_line
			(start -0.12065 0.3048)
			(end -0.67945 0.3048)
			(stroke
				(width 0.1)
				(type default)
			)
			(layer "F.Fab")
		)
		(fp_line
			(start -0.12065 0.2794)
			(end -0.12065 0.3048)
			(stroke
				(width 0.1)
				(type default)
			)
			(layer "F.Fab")
		)
		(fp_line
			(start -0.12065 -0.2794)
			(end 0.12065 -0.2794)
			(stroke
				(width 0.1)
				(type default)
			)
			(layer "F.Fab")
		)
		(fp_line
			(start -0.12065 -0.305054)
			(end -0.12065 -0.2794)
			(stroke
				(width 0.1)
				(type default)
			)
			(layer "F.Fab")
		)
		(fp_line
			(start -0.67945 0.3048)
			(end -0.67945 -0.305054)
			(stroke
				(width 0.1)
				(type default)
			)
			(layer "F.Fab")
		)
		(fp_line
			(start -0.67945 -0.305054)
			(end -0.12065 -0.305054)
			(stroke
				(width 0.1)
				(type default)
			)
			(layer "F.Fab")
		)
		(pad "1" smd circle
			(at -0.40005 0 180)
			(size 0 0)
			(layers "F.Cu" "F.Mask" "F.Paste")
			(net "FAN_1_PWM_IL_R")
		)
		(pad "2" smd circle
			(at 0.40005 0 180)
			(size 0 0)
			(layers "F.Cu" "F.Mask" "F.Paste")
			(net "GND")
		)
	)
	(footprint ""
		(layer "F.Cu")
		(at 18.669 -103.124)
		(property "Reference" "R5314"
			(at 0 0 0)
			(layer "F.SilkS")
			(hide yes)
			(effects
				(font
					(size 1.27 1.27)
				)
			)
		)
		(property "Value" ""
			(at 0 0 0)
			(layer "F.Fab")
			(effects
				(font
					(size 1.27 1.27)
				)
			)
		)
		(duplicate_pad_numbers_are_jumpers no)
		(fp_line
			(start -0.7874 -0.4064)
			(end 0.7874 -0.4064)
			(stroke
				(width 0.1524)
				(type default)
			)
			(layer "F.SilkS")
		)
		(fp_line
			(start -0.7874 0.4064)
			(end -0.7874 -0.4064)
			(stroke
				(width 0.1524)
				(type default)
			)
			(layer "F.SilkS")
		)
		(fp_line
			(start 0.7874 -0.4064)
			(end 0.7874 0.4064)
			(stroke
				(width 0.1524)
				(type default)
			)
			(layer "F.SilkS")
		)
		(fp_line
			(start 0.7874 0.4064)
			(end -0.7874 0.4064)
			(stroke
				(width 0.1524)
				(type default)
			)
			(layer "F.SilkS")
		)
		(fp_line
			(start -0.67945 -0.305054)
			(end -0.12065 -0.305054)
			(stroke
				(width 0.1)
				(type default)
			)
			(layer "F.Fab")
		)
		(fp_line
			(start -0.67945 0.3048)
			(end -0.67945 -0.305054)
			(stroke
				(width 0.1)
				(type default)
			)
			(layer "F.Fab")
		)
		(fp_line
			(start -0.12065 -0.305054)
			(end -0.12065 -0.2794)
			(stroke
				(width 0.1)
				(type default)
			)
			(layer "F.Fab")
		)
		(fp_line
			(start -0.12065 -0.2794)
			(end 0.12065 -0.2794)
			(stroke
				(width 0.1)
				(type default)
			)
			(layer "F.Fab")
		)
		(fp_line
			(start -0.12065 0.2794)
			(end -0.12065 0.3048)
			(stroke
				(width 0.1)
				(type default)
			)
			(layer "F.Fab")
		)
		(fp_line
			(start -0.12065 0.3048)
			(end -0.67945 0.3048)
			(stroke
				(width 0.1)
				(type default)
			)
			(layer "F.Fab")
		)
		(fp_line
			(start 0.120396 0.2794)
			(end -0.12065 0.2794)
			(stroke
				(width 0.1)
				(type default)
			)
			(layer "F.Fab")
		)
		(fp_line
			(start 0.120396 0.3048)
			(end 0.120396 0.2794)
			(stroke
				(width 0.1)
				(type default)
			)
			(layer "F.Fab")
		)
		(fp_line
			(start 0.12065 -0.3048)
			(end 0.67945 -0.3048)
			(stroke
				(width 0.1)
				(type default)
			)
			(layer "F.Fab")
		)
		(fp_line
			(start 0.12065 -0.2794)
			(end 0.12065 -0.3048)
			(stroke
				(width 0.1)
				(type default)
			)
			(layer "F.Fab")
		)
		(fp_line
			(start 0.67945 -0.3048)
			(end 0.67945 0.3048)
			(stroke
				(width 0.1)
				(type default)
			)
			(layer "F.Fab")
		)
		(fp_line
			(start 0.67945 0.3048)
			(end 0.120396 0.3048)
			(stroke
				(width 0.1)
				(type default)
			)
			(layer "F.Fab")
		)
		(pad "1" smd rect
			(at -0.40005 0 180)
			(size 0.4572 0.508)
			(layers "F.Cu" "F.Mask" "F.Paste")
			(net "FAN_5_TACH_IL_R")
		)
		(pad "2" smd rect
			(at 0.40005 0 180)
			(size 0.4572 0.508)
			(layers "F.Cu" "F.Mask" "F.Paste")
			(net "FAN_5_TACH_IL")
		)
	)
	(footprint ""
		(layer "F.Cu")
		(at 14.351 -294.64 180)
		(property "Reference" "R5698"
			(at 0 0 180)
			(layer "F.SilkS")
			(hide yes)
			(effects
				(font
					(size 1.27 1.27)
				)
			)
		)
		(property "Value" ""
			(at 0 0 180)
			(layer "F.Fab")
			(effects
				(font
					(size 1.27 1.27)
				)
			)
		)
		(duplicate_pad_numbers_are_jumpers no)
		(fp_line
			(start 0.7874 0.4064)
			(end -0.7874 0.4064)
			(stroke
				(width 0.1524)
				(type default)
			)
			(layer "F.SilkS")
		)
		(fp_line
			(start 0.7874 -0.4064)
			(end 0.7874 0.4064)
			(stroke
				(width 0.1524)
				(type default)
			)
			(layer "F.SilkS")
		)
		(fp_line
			(start -0.7874 0.4064)
			(end -0.7874 -0.4064)
			(stroke
				(width 0.1524)
				(type default)
			)
			(layer "F.SilkS")
		)
		(fp_line
			(start -0.7874 -0.4064)
			(end 0.7874 -0.4064)
			(stroke
				(width 0.1524)
				(type default)
			)
			(layer "F.SilkS")
		)
		(fp_line
			(start 0.67945 0.3048)
			(end 0.120396 0.3048)
			(stroke
				(width 0.1)
				(type default)
			)
			(layer "F.Fab")
		)
		(fp_line
			(start 0.67945 -0.3048)
			(end 0.67945 0.3048)
			(stroke
				(width 0.1)
				(type default)
			)
			(layer "F.Fab")
		)
		(fp_line
			(start 0.12065 -0.2794)
			(end 0.12065 -0.3048)
			(stroke
				(width 0.1)
				(type default)
			)
			(layer "F.Fab")
		)
		(fp_line
			(start 0.12065 -0.3048)
			(end 0.67945 -0.3048)
			(stroke
				(width 0.1)
				(type default)
			)
			(layer "F.Fab")
		)
		(fp_line
			(start 0.120396 0.3048)
			(end 0.120396 0.2794)
			(stroke
				(width 0.1)
				(type default)
			)
			(layer "F.Fab")
		)
		(fp_line
			(start 0.120396 0.2794)
			(end -0.12065 0.2794)
			(stroke
				(width 0.1)
				(type default)
			)
			(layer "F.Fab")
		)
		(fp_line
			(start -0.12065 0.3048)
			(end -0.67945 0.3048)
			(stroke
				(width 0.1)
				(type default)
			)
			(layer "F.Fab")
		)
		(fp_line
			(start -0.12065 0.2794)
			(end -0.12065 0.3048)
			(stroke
				(width 0.1)
				(type default)
			)
			(layer "F.Fab")
		)
		(fp_line
			(start -0.12065 -0.2794)
			(end 0.12065 -0.2794)
			(stroke
				(width 0.1)
				(type default)
			)
			(layer "F.Fab")
		)
		(fp_line
			(start -0.12065 -0.305054)
			(end -0.12065 -0.2794)
			(stroke
				(width 0.1)
				(type default)
			)
			(layer "F.Fab")
		)
		(fp_line
			(start -0.67945 0.3048)
			(end -0.67945 -0.305054)
			(stroke
				(width 0.1)
				(type default)
			)
			(layer "F.Fab")
		)
		(fp_line
			(start -0.67945 -0.305054)
			(end -0.12065 -0.305054)
			(stroke
				(width 0.1)
				(type default)
			)
			(layer "F.Fab")
		)
		(pad "1" smd rect
			(at -0.40005 0)
			(size 0.4572 0.508)
			(layers "F.Cu" "F.Mask" "F.Paste")
			(net "P12V_LED_R_FAN7")
		)
		(pad "2" smd rect
			(at 0.40005 0)
			(size 0.4572 0.508)
			(layers "F.Cu" "F.Mask" "F.Paste")
			(net "P12V_LED_R1_FAN7")
		)
	)
	(footprint ""
		(layer "F.Cu")
		(at 23.241 -211.328 -90)
		(property "Reference" "R5512"
			(at 0 0 270)
			(layer "F.SilkS")
			(hide yes)
			(effects
				(font
					(size 1.27 1.27)
				)
			)
		)
		(property "Value" ""
			(at 0 0 270)
			(layer "F.Fab")
			(effects
				(font
					(size 1.27 1.27)
				)
			)
		)
		(duplicate_pad_numbers_are_jumpers no)
		(fp_line
			(start -0.7874 0.4064)
			(end -0.7874 -0.4064)
			(stroke
				(width 0.1524)
				(type default)
			)
			(layer "F.SilkS")
		)
		(fp_line
			(start 0.7874 0.4064)
			(end -0.7874 0.4064)
			(stroke
				(width 0.1524)
				(type default)
			)
			(layer "F.SilkS")
		)
		(fp_line
			(start -0.7874 -0.4064)
			(end 0.7874 -0.4064)
			(stroke
				(width 0.1524)
				(type default)
			)
			(layer "F.SilkS")
		)
		(fp_line
			(start 0.7874 -0.4064)
			(end 0.7874 0.4064)
			(stroke
				(width 0.1524)
				(type default)
			)
			(layer "F.SilkS")
		)
		(fp_line
			(start -0.67945 0.3048)
			(end -0.67945 -0.305054)
			(stroke
				(width 0.1)
				(type default)
			)
			(layer "F.Fab")
		)
		(fp_line
			(start -0.12065 0.3048)
			(end -0.67945 0.3048)
			(stroke
				(width 0.1)
				(type default)
			)
			(layer "F.Fab")
		)
		(fp_line
			(start 0.120396 0.3048)
			(end 0.120396 0.2794)
			(stroke
				(width 0.1)
				(type default)
			)
			(layer "F.Fab")
		)
		(fp_line
			(start 0.67945 0.3048)
			(end 0.120396 0.3048)
			(stroke
				(width 0.1)
				(type default)
			)
			(layer "F.Fab")
		)
		(fp_line
			(start -0.12065 0.2794)
			(end -0.12065 0.3048)
			(stroke
				(width 0.1)
				(type default)
			)
			(layer "F.Fab")
		)
		(fp_line
			(start 0.120396 0.2794)
			(end -0.12065 0.2794)
			(stroke
				(width 0.1)
				(type default)
			)
			(layer "F.Fab")
		)
		(fp_line
			(start -0.12065 -0.2794)
			(end 0.12065 -0.2794)
			(stroke
				(width 0.1)
				(type default)
			)
			(layer "F.Fab")
		)
		(fp_line
			(start 0.12065 -0.2794)
			(end 0.12065 -0.3048)
			(stroke
				(width 0.1)
				(type default)
			)
			(layer "F.Fab")
		)
		(fp_line
			(start 0.12065 -0.3048)
			(end 0.67945 -0.3048)
			(stroke
				(width 0.1)
				(type default)
			)
			(layer "F.Fab")
		)
		(fp_line
			(start 0.67945 -0.3048)
			(end 0.67945 0.3048)
			(stroke
				(width 0.1)
				(type default)
			)
			(layer "F.Fab")
		)
		(fp_line
			(start -0.67945 -0.305054)
			(end -0.12065 -0.305054)
			(stroke
				(width 0.1)
				(type default)
			)
			(layer "F.Fab")
		)
		(fp_line
			(start -0.12065 -0.305054)
			(end -0.12065 -0.2794)
			(stroke
				(width 0.1)
				(type default)
			)
			(layer "F.Fab")
		)
		(pad "1" smd circle
			(at -0.40005 0 270)
			(size 0 0)
			(layers "F.Cu" "F.Mask" "F.Paste")
			(net "P3V3_AUX")
		)
		(pad "2" smd circle
			(at 0.40005 0 270)
			(size 0 0)
			(layers "F.Cu" "F.Mask" "F.Paste")
			(net "FAN_1_PWM_BUF")
		)
	)
	(footprint ""
		(layer "F.Cu")
		(at 37.338 -299.339 180)
		(property "Reference" "R5186"
			(at 0 0 180)
			(layer "F.SilkS")
			(hide yes)
			(effects
				(font
					(size 1.27 1.27)
				)
			)
		)
		(property "Value" ""
			(at 0 0 180)
			(layer "F.Fab")
			(effects
				(font
					(size 1.27 1.27)
				)
			)
		)
		(duplicate_pad_numbers_are_jumpers no)
		(fp_line
			(start 0.7874 0.4064)
			(end -0.7874 0.4064)
			(stroke
				(width 0.1524)
				(type default)
			)
			(layer "F.SilkS")
		)
		(fp_line
			(start 0.7874 -0.4064)
			(end 0.7874 0.4064)
			(stroke
				(width 0.1524)
				(type default)
			)
			(layer "F.SilkS")
		)
		(fp_line
			(start -0.7874 0.4064)
			(end -0.7874 -0.4064)
			(stroke
				(width 0.1524)
				(type default)
			)
			(layer "F.SilkS")
		)
		(fp_line
			(start -0.7874 -0.4064)
			(end 0.7874 -0.4064)
			(stroke
				(width 0.1524)
				(type default)
			)
			(layer "F.SilkS")
		)
		(fp_line
			(start 0.67945 0.3048)
			(end 0.120396 0.3048)
			(stroke
				(width 0.1)
				(type default)
			)
			(layer "F.Fab")
		)
		(fp_line
			(start 0.67945 -0.3048)
			(end 0.67945 0.3048)
			(stroke
				(width 0.1)
				(type default)
			)
			(layer "F.Fab")
		)
		(fp_line
			(start 0.12065 -0.2794)
			(end 0.12065 -0.3048)
			(stroke
				(width 0.1)
				(type default)
			)
			(layer "F.Fab")
		)
		(fp_line
			(start 0.12065 -0.3048)
			(end 0.67945 -0.3048)
			(stroke
				(width 0.1)
				(type default)
			)
			(layer "F.Fab")
		)
		(fp_line
			(start 0.120396 0.3048)
			(end 0.120396 0.2794)
			(stroke
				(width 0.1)
				(type default)
			)
			(layer "F.Fab")
		)
		(fp_line
			(start 0.120396 0.2794)
			(end -0.12065 0.2794)
			(stroke
				(width 0.1)
				(type default)
			)
			(layer "F.Fab")
		)
		(fp_line
			(start -0.12065 0.3048)
			(end -0.67945 0.3048)
			(stroke
				(width 0.1)
				(type default)
			)
			(layer "F.Fab")
		)
		(fp_line
			(start -0.12065 0.2794)
			(end -0.12065 0.3048)
			(stroke
				(width 0.1)
				(type default)
			)
			(layer "F.Fab")
		)
		(fp_line
			(start -0.12065 -0.2794)
			(end 0.12065 -0.2794)
			(stroke
				(width 0.1)
				(type default)
			)
			(layer "F.Fab")
		)
		(fp_line
			(start -0.12065 -0.305054)
			(end -0.12065 -0.2794)
			(stroke
				(width 0.1)
				(type default)
			)
			(layer "F.Fab")
		)
		(fp_line
			(start -0.67945 0.3048)
			(end -0.67945 -0.305054)
			(stroke
				(width 0.1)
				(type default)
			)
			(layer "F.Fab")
		)
		(fp_line
			(start -0.67945 -0.305054)
			(end -0.12065 -0.305054)
			(stroke
				(width 0.1)
				(type default)
			)
			(layer "F.Fab")
		)
		(pad "1" smd circle
			(at -0.40005 0 180)
			(size 0 0)
			(layers "F.Cu" "F.Mask" "F.Paste")
			(net "FAN_0_PWM_IL_R")
		)
		(pad "2" smd circle
			(at 0.40005 0 180)
			(size 0 0)
			(layers "F.Cu" "F.Mask" "F.Paste")
			(net "FAN_0_PWM_IL")
		)
	)
)
